(kicad_pcb
	(version 20260206)
	(generator "pcbnew")
	(generator_version "10.0")
	(general
		(thickness 1.6)
		(legacy_teardrops no)
	)
	(paper "A4")
	(title_block
		(title "04192023_DAF0TMB3IC0_F0TG_MB_C_brd_V02_OCP.brd")
		(comment 1 "Grand Teton / footprints 2515-2522 of 8354")
	)
	(layers
		(0 "F.Cu" signal "TOP")
		(4 "In1.Cu" signal "GND")
		(6 "In2.Cu" signal "IN1")
		(8 "In3.Cu" signal "GND1")
		(10 "In4.Cu" signal "IN2")
		(12 "In5.Cu" signal "GND2")
		(14 "In6.Cu" signal "IN3")
		(16 "In7.Cu" signal "GND3")
		(18 "In8.Cu" signal "VCC")
		(20 "In9.Cu" signal "VCC1")
		(22 "In10.Cu" signal "GND4")
		(24 "In11.Cu" signal "IN4")
		(26 "In12.Cu" signal "GND5")
		(28 "In13.Cu" signal "IN5")
		(30 "In14.Cu" signal "GND6")
		(32 "In15.Cu" signal "IN6")
		(34 "In16.Cu" signal "GND7")
		(2 "B.Cu" signal "BOTTOM")
		(9 "F.Adhes" user "F.Adhesive")
		(11 "B.Adhes" user "B.Adhesive")
		(13 "F.Paste" user "Package Geometry/Pastemask Top")
		(15 "B.Paste" user "Package Geometry/Pastemask Bottom")
		(5 "F.SilkS" user "Ref Des/Silkscreen Top")
		(7 "B.SilkS" user "Ref Des/Silkscreen Bottom")
		(1 "F.Mask" user "Board Geometry/Soldermask Top")
		(3 "B.Mask" user "Board Geometry/Soldermask Bottom")
		(17 "Dwgs.User" user "User.Drawings")
		(19 "Cmts.User" user "User.Comments")
		(21 "Eco1.User" user "User.Eco1")
		(23 "Eco2.User" user "User.Eco2")
		(25 "Edge.Cuts" user "Board Geometry/Outline")
		(27 "Margin" user)
		(31 "F.CrtYd" user "Package Geometry/Place Bound Top")
		(29 "B.CrtYd" user "Package Geometry/Place Bound Bottom")
		(35 "F.Fab" user "Ref Des/Assembly Top")
		(33 "B.Fab" user "Ref Des/Assembly Bottom")
	)
	(footprint ""
		(layer "F.Cu")
		(at 194.183 -129.377948 90)
		(property "Reference" "R1202"
			(at 0 0 90)
			(layer "F.SilkS")
			(hide yes)
			(effects
				(font
					(size 1.27 1.27)
				)
			)
		)
		(property "Value" ""
			(at 0 0 90)
			(layer "F.Fab")
			(effects
				(font
					(size 1.27 1.27)
				)
			)
		)
		(duplicate_pad_numbers_are_jumpers no)
		(fp_line
			(start 0.7874 -0.4064)
			(end 0.7874 0.4064)
			(stroke
				(width 0.1524)
				(type default)
			)
			(layer "F.SilkS")
		)
		(fp_line
			(start -0.7874 -0.4064)
			(end 0.7874 -0.4064)
			(stroke
				(width 0.1524)
				(type default)
			)
			(layer "F.SilkS")
		)
		(fp_line
			(start 0.7874 0.4064)
			(end -0.7874 0.4064)
			(stroke
				(width 0.1524)
				(type default)
			)
			(layer "F.SilkS")
		)
		(fp_line
			(start -0.7874 0.4064)
			(end -0.7874 -0.4064)
			(stroke
				(width 0.1524)
				(type default)
			)
			(layer "F.SilkS")
		)
		(fp_line
			(start -0.12065 -0.305054)
			(end -0.12065 -0.2794)
			(stroke
				(width 0.1)
				(type default)
			)
			(layer "F.Fab")
		)
		(fp_line
			(start -0.67945 -0.305054)
			(end -0.12065 -0.305054)
			(stroke
				(width 0.1)
				(type default)
			)
			(layer "F.Fab")
		)
		(fp_line
			(start 0.67945 -0.3048)
			(end 0.67945 0.3048)
			(stroke
				(width 0.1)
				(type default)
			)
			(layer "F.Fab")
		)
		(fp_line
			(start 0.12065 -0.3048)
			(end 0.67945 -0.3048)
			(stroke
				(width 0.1)
				(type default)
			)
			(layer "F.Fab")
		)
		(fp_line
			(start 0.12065 -0.2794)
			(end 0.12065 -0.3048)
			(stroke
				(width 0.1)
				(type default)
			)
			(layer "F.Fab")
		)
		(fp_line
			(start -0.12065 -0.2794)
			(end 0.12065 -0.2794)
			(stroke
				(width 0.1)
				(type default)
			)
			(layer "F.Fab")
		)
		(fp_line
			(start 0.120396 0.2794)
			(end -0.12065 0.2794)
			(stroke
				(width 0.1)
				(type default)
			)
			(layer "F.Fab")
		)
		(fp_line
			(start -0.12065 0.2794)
			(end -0.12065 0.3048)
			(stroke
				(width 0.1)
				(type default)
			)
			(layer "F.Fab")
		)
		(fp_line
			(start 0.67945 0.3048)
			(end 0.120396 0.3048)
			(stroke
				(width 0.1)
				(type default)
			)
			(layer "F.Fab")
		)
		(fp_line
			(start 0.120396 0.3048)
			(end 0.120396 0.2794)
			(stroke
				(width 0.1)
				(type default)
			)
			(layer "F.Fab")
		)
		(fp_line
			(start -0.12065 0.3048)
			(end -0.67945 0.3048)
			(stroke
				(width 0.1)
				(type default)
			)
			(layer "F.Fab")
		)
		(fp_line
			(start -0.67945 0.3048)
			(end -0.67945 -0.305054)
			(stroke
				(width 0.1)
				(type default)
			)
			(layer "F.Fab")
		)
		(pad "1" smd circle
			(at -0.40005 0 90)
			(size 0 0)
			(layers "F.Cu" "F.Mask" "F.Paste")
			(net "FM_FORCE_ALL_PWRON_R")
		)
		(pad "2" smd circle
			(at 0.40005 0 90)
			(size 0 0)
			(layers "F.Cu" "F.Mask" "F.Paste")
			(net "FM_FORCE_ALL_PWRON")
		)
	)
	(footprint ""
		(layer "F.Cu")
		(at 99.015296 -422.43248 90)
		(property "Reference" "R4203"
			(at 0 0 90)
			(layer "F.SilkS")
			(hide yes)
			(effects
				(font
					(size 1.27 1.27)
				)
			)
		)
		(property "Value" ""
			(at 0 0 90)
			(layer "F.Fab")
			(effects
				(font
					(size 1.27 1.27)
				)
			)
		)
		(duplicate_pad_numbers_are_jumpers no)
		(fp_line
			(start 0.7874 -0.4064)
			(end 0.7874 0.4064)
			(stroke
				(width 0.1524)
				(type default)
			)
			(layer "F.SilkS")
		)
		(fp_line
			(start -0.7874 -0.4064)
			(end 0.7874 -0.4064)
			(stroke
				(width 0.1524)
				(type default)
			)
			(layer "F.SilkS")
		)
		(fp_line
			(start 0.7874 0.4064)
			(end -0.7874 0.4064)
			(stroke
				(width 0.1524)
				(type default)
			)
			(layer "F.SilkS")
		)
		(fp_line
			(start -0.7874 0.4064)
			(end -0.7874 -0.4064)
			(stroke
				(width 0.1524)
				(type default)
			)
			(layer "F.SilkS")
		)
		(fp_line
			(start -0.12065 -0.305054)
			(end -0.12065 -0.2794)
			(stroke
				(width 0.1)
				(type default)
			)
			(layer "F.Fab")
		)
		(fp_line
			(start -0.67945 -0.305054)
			(end -0.12065 -0.305054)
			(stroke
				(width 0.1)
				(type default)
			)
			(layer "F.Fab")
		)
		(fp_line
			(start 0.67945 -0.3048)
			(end 0.67945 0.3048)
			(stroke
				(width 0.1)
				(type default)
			)
			(layer "F.Fab")
		)
		(fp_line
			(start 0.12065 -0.3048)
			(end 0.67945 -0.3048)
			(stroke
				(width 0.1)
				(type default)
			)
			(layer "F.Fab")
		)
		(fp_line
			(start 0.12065 -0.2794)
			(end 0.12065 -0.3048)
			(stroke
				(width 0.1)
				(type default)
			)
			(layer "F.Fab")
		)
		(fp_line
			(start -0.12065 -0.2794)
			(end 0.12065 -0.2794)
			(stroke
				(width 0.1)
				(type default)
			)
			(layer "F.Fab")
		)
		(fp_line
			(start 0.120396 0.2794)
			(end -0.12065 0.2794)
			(stroke
				(width 0.1)
				(type default)
			)
			(layer "F.Fab")
		)
		(fp_line
			(start -0.12065 0.2794)
			(end -0.12065 0.3048)
			(stroke
				(width 0.1)
				(type default)
			)
			(layer "F.Fab")
		)
		(fp_line
			(start 0.67945 0.3048)
			(end 0.120396 0.3048)
			(stroke
				(width 0.1)
				(type default)
			)
			(layer "F.Fab")
		)
		(fp_line
			(start 0.120396 0.3048)
			(end 0.120396 0.2794)
			(stroke
				(width 0.1)
				(type default)
			)
			(layer "F.Fab")
		)
		(fp_line
			(start -0.12065 0.3048)
			(end -0.67945 0.3048)
			(stroke
				(width 0.1)
				(type default)
			)
			(layer "F.Fab")
		)
		(fp_line
			(start -0.67945 0.3048)
			(end -0.67945 -0.305054)
			(stroke
				(width 0.1)
				(type default)
			)
			(layer "F.Fab")
		)
		(pad "1" smd circle
			(at -0.40005 0 90)
			(size 0 0)
			(layers "F.Cu" "F.Mask" "F.Paste")
			(net "U272_2_ADD0")
		)
		(pad "2" smd circle
			(at 0.40005 0 90)
			(size 0 0)
			(layers "F.Cu" "F.Mask" "F.Paste")
			(net "GND")
		)
	)
	(footprint ""
		(layer "F.Cu")
		(at 438.056782 -435.27726 90)
		(property "Reference" "R3471"
			(at 0 0 90)
			(layer "F.SilkS")
			(hide yes)
			(effects
				(font
					(size 1.27 1.27)
				)
			)
		)
		(property "Value" ""
			(at 0 0 90)
			(layer "F.Fab")
			(effects
				(font
					(size 1.27 1.27)
				)
			)
		)
		(duplicate_pad_numbers_are_jumpers no)
		(fp_line
			(start 0.7874 -0.4064)
			(end 0.7874 0.4064)
			(stroke
				(width 0.1524)
				(type default)
			)
			(layer "F.SilkS")
		)
		(fp_line
			(start -0.7874 -0.4064)
			(end 0.7874 -0.4064)
			(stroke
				(width 0.1524)
				(type default)
			)
			(layer "F.SilkS")
		)
		(fp_line
			(start 0.7874 0.4064)
			(end -0.7874 0.4064)
			(stroke
				(width 0.1524)
				(type default)
			)
			(layer "F.SilkS")
		)
		(fp_line
			(start -0.7874 0.4064)
			(end -0.7874 -0.4064)
			(stroke
				(width 0.1524)
				(type default)
			)
			(layer "F.SilkS")
		)
		(fp_line
			(start -0.12065 -0.305054)
			(end -0.12065 -0.2794)
			(stroke
				(width 0.1)
				(type default)
			)
			(layer "F.Fab")
		)
		(fp_line
			(start -0.67945 -0.305054)
			(end -0.12065 -0.305054)
			(stroke
				(width 0.1)
				(type default)
			)
			(layer "F.Fab")
		)
		(fp_line
			(start 0.67945 -0.3048)
			(end 0.67945 0.3048)
			(stroke
				(width 0.1)
				(type default)
			)
			(layer "F.Fab")
		)
		(fp_line
			(start 0.12065 -0.3048)
			(end 0.67945 -0.3048)
			(stroke
				(width 0.1)
				(type default)
			)
			(layer "F.Fab")
		)
		(fp_line
			(start 0.12065 -0.2794)
			(end 0.12065 -0.3048)
			(stroke
				(width 0.1)
				(type default)
			)
			(layer "F.Fab")
		)
		(fp_line
			(start -0.12065 -0.2794)
			(end 0.12065 -0.2794)
			(stroke
				(width 0.1)
				(type default)
			)
			(layer "F.Fab")
		)
		(fp_line
			(start 0.120396 0.2794)
			(end -0.12065 0.2794)
			(stroke
				(width 0.1)
				(type default)
			)
			(layer "F.Fab")
		)
		(fp_line
			(start -0.12065 0.2794)
			(end -0.12065 0.3048)
			(stroke
				(width 0.1)
				(type default)
			)
			(layer "F.Fab")
		)
		(fp_line
			(start 0.67945 0.3048)
			(end 0.120396 0.3048)
			(stroke
				(width 0.1)
				(type default)
			)
			(layer "F.Fab")
		)
		(fp_line
			(start 0.120396 0.3048)
			(end 0.120396 0.2794)
			(stroke
				(width 0.1)
				(type default)
			)
			(layer "F.Fab")
		)
		(fp_line
			(start -0.12065 0.3048)
			(end -0.67945 0.3048)
			(stroke
				(width 0.1)
				(type default)
			)
			(layer "F.Fab")
		)
		(fp_line
			(start -0.67945 0.3048)
			(end -0.67945 -0.305054)
			(stroke
				(width 0.1)
				(type default)
			)
			(layer "F.Fab")
		)
		(pad "1" smd circle
			(at -0.40005 0 90)
			(size 0 0)
			(layers "F.Cu" "F.Mask" "F.Paste")
			(net "GPU_WP_HW_CTRL_N")
		)
		(pad "2" smd circle
			(at 0.40005 0 90)
			(size 0 0)
			(layers "F.Cu" "F.Mask" "F.Paste")
			(net "GND")
		)
	)
	(footprint ""
		(layer "F.Cu")
		(at 139.420092 -355.91242)
		(property "Reference" "ME6"
			(at 0.1143 -8.208518 0)
			(unlocked yes)
			(layer "F.SilkS")
			(effects
				(font
					(size 0.254 0.127)
					(thickness 0.000001)
				)
				(justify left)
			)
		)
		(property "Value" ""
			(at 0 0 0)
			(layer "F.Fab")
			(effects
				(font
					(size 1.27 1.27)
				)
			)
		)
		(duplicate_pad_numbers_are_jumpers no)
		(fp_poly
			(pts
				(xy 0 0) (xy 14.99997 0) (xy 14.99997 -7.999984) (xy 0 -7.999984)
			)
			(stroke
				(width 0)
				(type default)
			)
			(fill no)
			(layer "F.CrtYd")
		)
	)
	(footprint ""
		(layer "F.Cu")
		(at 401.128484 -402.548852 -90)
		(property "Reference" "R1048"
			(at 0 0 270)
			(layer "F.SilkS")
			(hide yes)
			(effects
				(font
					(size 1.27 1.27)
				)
			)
		)
		(property "Value" ""
			(at 0 0 270)
			(layer "F.Fab")
			(effects
				(font
					(size 1.27 1.27)
				)
			)
		)
		(duplicate_pad_numbers_are_jumpers no)
		(fp_line
			(start -0.32512 0.175006)
			(end -0.32512 -0.175006)
			(stroke
				(width 0.1)
				(type default)
			)
			(layer "F.Fab")
		)
		(fp_line
			(start 0.32512 0.175006)
			(end -0.32512 0.175006)
			(stroke
				(width 0.1)
				(type default)
			)
			(layer "F.Fab")
		)
		(fp_line
			(start -0.32512 -0.175006)
			(end 0.32512 -0.175006)
			(stroke
				(width 0.1)
				(type default)
			)
			(layer "F.Fab")
		)
		(fp_line
			(start 0.32512 -0.175006)
			(end 0.32512 0.175006)
			(stroke
				(width 0.1)
				(type default)
			)
			(layer "F.Fab")
		)
		(pad "1" smd rect
			(at -0.2667 0 270)
			(size 0.3048 0.381)
			(layers "F.Cu" "F.Mask" "F.Paste")
			(net "MODE_RT_CPU0_P2")
		)
		(pad "2" smd rect
			(at 0.2667 0 90)
			(size 0.3048 0.381)
			(layers "F.Cu" "F.Mask" "F.Paste")
			(net "GND")
		)
	)
	(footprint ""
		(layer "F.Cu")
		(at 58.580782 -145.066766)
		(property "Reference" "PC21"
			(at 0 0 0)
			(layer "F.SilkS")
			(hide yes)
			(effects
				(font
					(size 1.27 1.27)
				)
			)
		)
		(property "Value" ""
			(at 0 0 0)
			(layer "F.Fab")
			(effects
				(font
					(size 1.27 1.27)
				)
			)
		)
		(duplicate_pad_numbers_are_jumpers no)
		(fp_line
			(start -0.7874 -0.4064)
			(end 0.7874 -0.4064)
			(stroke
				(width 0.1524)
				(type default)
			)
			(layer "F.SilkS")
		)
		(fp_line
			(start -0.7874 0.4064)
			(end -0.7874 -0.4064)
			(stroke
				(width 0.1524)
				(type default)
			)
			(layer "F.SilkS")
		)
		(fp_line
			(start 0.7874 -0.4064)
			(end 0.7874 0.4064)
			(stroke
				(width 0.1524)
				(type default)
			)
			(layer "F.SilkS")
		)
		(fp_line
			(start 0.7874 0.4064)
			(end -0.7874 0.4064)
			(stroke
				(width 0.1524)
				(type default)
			)
			(layer "F.SilkS")
		)
		(fp_line
			(start -0.67945 -0.305054)
			(end -0.12065 -0.305054)
			(stroke
				(width 0.1)
				(type default)
			)
			(layer "F.Fab")
		)
		(fp_line
			(start -0.67945 0.3048)
			(end -0.67945 -0.305054)
			(stroke
				(width 0.1)
				(type default)
			)
			(layer "F.Fab")
		)
		(fp_line
			(start -0.12065 -0.305054)
			(end -0.12065 -0.2794)
			(stroke
				(width 0.1)
				(type default)
			)
			(layer "F.Fab")
		)
		(fp_line
			(start -0.12065 -0.2794)
			(end 0.12065 -0.2794)
			(stroke
				(width 0.1)
				(type default)
			)
			(layer "F.Fab")
		)
		(fp_line
			(start -0.12065 0.2794)
			(end -0.12065 0.3048)
			(stroke
				(width 0.1)
				(type default)
			)
			(layer "F.Fab")
		)
		(fp_line
			(start -0.12065 0.3048)
			(end -0.67945 0.3048)
			(stroke
				(width 0.1)
				(type default)
			)
			(layer "F.Fab")
		)
		(fp_line
			(start 0.120396 0.2794)
			(end -0.12065 0.2794)
			(stroke
				(width 0.1)
				(type default)
			)
			(layer "F.Fab")
		)
		(fp_line
			(start 0.120396 0.3048)
			(end 0.120396 0.2794)
			(stroke
				(width 0.1)
				(type default)
			)
			(layer "F.Fab")
		)
		(fp_line
			(start 0.12065 -0.3048)
			(end 0.67945 -0.3048)
			(stroke
				(width 0.1)
				(type default)
			)
			(layer "F.Fab")
		)
		(fp_line
			(start 0.12065 -0.2794)
			(end 0.12065 -0.3048)
			(stroke
				(width 0.1)
				(type default)
			)
			(layer "F.Fab")
		)
		(fp_line
			(start 0.67945 -0.3048)
			(end 0.67945 0.3048)
			(stroke
				(width 0.1)
				(type default)
			)
			(layer "F.Fab")
		)
		(fp_line
			(start 0.67945 0.3048)
			(end 0.120396 0.3048)
			(stroke
				(width 0.1)
				(type default)
			)
			(layer "F.Fab")
		)
		(pad "1" smd circle
			(at -0.40005 0)
			(size 0 0)
			(layers "F.Cu" "F.Mask" "F.Paste")
			(net "PVDD18_S5_P1")
		)
		(pad "2" smd circle
			(at 0.40005 0)
			(size 0 0)
			(layers "F.Cu" "F.Mask" "F.Paste")
			(net "GND")
		)
	)
	(footprint ""
		(layer "F.Cu")
		(at 144.386554 -321.695572 -90)
		(property "Reference" "R551"
			(at 0 0 270)
			(layer "F.SilkS")
			(hide yes)
			(effects
				(font
					(size 1.27 1.27)
				)
			)
		)
		(property "Value" ""
			(at 0 0 270)
			(layer "F.Fab")
			(effects
				(font
					(size 1.27 1.27)
				)
			)
		)
		(duplicate_pad_numbers_are_jumpers no)
		(fp_line
			(start -0.7874 0.4064)
			(end -0.7874 -0.4064)
			(stroke
				(width 0.1524)
				(type default)
			)
			(layer "F.SilkS")
		)
		(fp_line
			(start 0.7874 0.4064)
			(end -0.7874 0.4064)
			(stroke
				(width 0.1524)
				(type default)
			)
			(layer "F.SilkS")
		)
		(fp_line
			(start -0.7874 -0.4064)
			(end 0.7874 -0.4064)
			(stroke
				(width 0.1524)
				(type default)
			)
			(layer "F.SilkS")
		)
		(fp_line
			(start 0.7874 -0.4064)
			(end 0.7874 0.4064)
			(stroke
				(width 0.1524)
				(type default)
			)
			(layer "F.SilkS")
		)
		(fp_line
			(start -0.67945 0.3048)
			(end -0.67945 -0.305054)
			(stroke
				(width 0.1)
				(type default)
			)
			(layer "F.Fab")
		)
		(fp_line
			(start -0.12065 0.3048)
			(end -0.67945 0.3048)
			(stroke
				(width 0.1)
				(type default)
			)
			(layer "F.Fab")
		)
		(fp_line
			(start 0.120396 0.3048)
			(end 0.120396 0.2794)
			(stroke
				(width 0.1)
				(type default)
			)
			(layer "F.Fab")
		)
		(fp_line
			(start 0.67945 0.3048)
			(end 0.120396 0.3048)
			(stroke
				(width 0.1)
				(type default)
			)
			(layer "F.Fab")
		)
		(fp_line
			(start -0.12065 0.2794)
			(end -0.12065 0.3048)
			(stroke
				(width 0.1)
				(type default)
			)
			(layer "F.Fab")
		)
		(fp_line
			(start 0.120396 0.2794)
			(end -0.12065 0.2794)
			(stroke
				(width 0.1)
				(type default)
			)
			(layer "F.Fab")
		)
		(fp_line
			(start -0.12065 -0.2794)
			(end 0.12065 -0.2794)
			(stroke
				(width 0.1)
				(type default)
			)
			(layer "F.Fab")
		)
		(fp_line
			(start 0.12065 -0.2794)
			(end 0.12065 -0.3048)
			(stroke
				(width 0.1)
				(type default)
			)
			(layer "F.Fab")
		)
		(fp_line
			(start 0.12065 -0.3048)
			(end 0.67945 -0.3048)
			(stroke
				(width 0.1)
				(type default)
			)
			(layer "F.Fab")
		)
		(fp_line
			(start 0.67945 -0.3048)
			(end 0.67945 0.3048)
			(stroke
				(width 0.1)
				(type default)
			)
			(layer "F.Fab")
		)
		(fp_line
			(start -0.67945 -0.305054)
			(end -0.12065 -0.305054)
			(stroke
				(width 0.1)
				(type default)
			)
			(layer "F.Fab")
		)
		(fp_line
			(start -0.12065 -0.305054)
			(end -0.12065 -0.2794)
			(stroke
				(width 0.1)
				(type default)
			)
			(layer "F.Fab")
		)
		(pad "1" smd circle
			(at -0.40005 0 270)
			(size 0 0)
			(layers "F.Cu" "F.Mask" "F.Paste")
			(net "CPU1_SPD_HOST_CTRL_N")
		)
		(pad "2" smd circle
			(at 0.40005 0 270)
			(size 0 0)
			(layers "F.Cu" "F.Mask" "F.Paste")
			(net "PVDD18_S5_P1")
		)
	)
	(footprint ""
		(layer "F.Cu")
		(at 52.17033 -17.623536 90)
		(property "Reference" "C704"
			(at 0 0 90)
			(layer "F.SilkS")
			(hide yes)
			(effects
				(font
					(size 1.27 1.27)
				)
			)
		)
		(property "Value" ""
			(at 0 0 90)
			(layer "F.Fab")
			(effects
				(font
					(size 1.27 1.27)
				)
			)
		)
		(duplicate_pad_numbers_are_jumpers no)
		(fp_line
			(start 0.299974 -0.150114)
			(end 0.299974 0.150114)
			(stroke
				(width 0.1)
				(type default)
			)
			(layer "F.Fab")
		)
		(fp_line
			(start -0.299974 -0.150114)
			(end 0.299974 -0.150114)
			(stroke
				(width 0.1)
				(type default)
			)
			(layer "F.Fab")
		)
		(fp_line
			(start 0.299974 0.150114)
			(end -0.299974 0.150114)
			(stroke
				(width 0.1)
				(type default)
			)
			(layer "F.Fab")
		)
		(fp_line
			(start -0.299974 0.150114)
			(end -0.299974 -0.150114)
			(stroke
				(width 0.1)
				(type default)
			)
			(layer "F.Fab")
		)
		(pad "1" smd rect
			(at -0.2667 0 90)
			(size 0.3048 0.381)
			(layers "F.Cu" "F.Mask" "F.Paste")
			(net "P5E_CPU1_G1_TX_C_DN<2>")
		)
		(pad "2" smd rect
			(at 0.2667 0 90)
			(size 0.3048 0.381)
			(layers "F.Cu" "F.Mask" "F.Paste")
			(net "P5E_CPU1_G1_TX_DN<2>")
		)
	)
)
